(kicad_pcb
	(version 20260206)
	(generator "pcbnew")
	(generator_version "10.0")
	(general
		(thickness 1.6)
		(legacy_teardrops no)
	)
	(paper "A4")
	(title_block
		(title "04192023_DAF0TMB3IC0_F0TG_MB_C_brd_V02_OCP.brd")
		(comment 1 "Grand Teton / footprints 5257-5263 of 8354")
	)
	(layers
		(0 "F.Cu" signal "TOP")
		(4 "In1.Cu" signal "GND")
		(6 "In2.Cu" signal "IN1")
		(8 "In3.Cu" signal "GND1")
		(10 "In4.Cu" signal "IN2")
		(12 "In5.Cu" signal "GND2")
		(14 "In6.Cu" signal "IN3")
		(16 "In7.Cu" signal "GND3")
		(18 "In8.Cu" signal "VCC")
		(20 "In9.Cu" signal "VCC1")
		(22 "In10.Cu" signal "GND4")
		(24 "In11.Cu" signal "IN4")
		(26 "In12.Cu" signal "GND5")
		(28 "In13.Cu" signal "IN5")
		(30 "In14.Cu" signal "GND6")
		(32 "In15.Cu" signal "IN6")
		(34 "In16.Cu" signal "GND7")
		(2 "B.Cu" signal "BOTTOM")
		(9 "F.Adhes" user "F.Adhesive")
		(11 "B.Adhes" user "B.Adhesive")
		(13 "F.Paste" user "Package Geometry/Pastemask Top")
		(15 "B.Paste" user "Package Geometry/Pastemask Bottom")
		(5 "F.SilkS" user "Ref Des/Silkscreen Top")
		(7 "B.SilkS" user "Ref Des/Silkscreen Bottom")
		(1 "F.Mask" user "Board Geometry/Soldermask Top")
		(3 "B.Mask" user "Board Geometry/Soldermask Bottom")
		(17 "Dwgs.User" user "User.Drawings")
		(19 "Cmts.User" user "User.Comments")
		(21 "Eco1.User" user "User.Eco1")
		(23 "Eco2.User" user "User.Eco2")
		(25 "Edge.Cuts" user "Board Geometry/Outline")
		(27 "Margin" user)
		(31 "F.CrtYd" user "Package Geometry/Place Bound Top")
		(29 "B.CrtYd" user "Package Geometry/Place Bound Bottom")
		(35 "F.Fab" user "Ref Des/Assembly Top")
		(33 "B.Fab" user "Ref Des/Assembly Bottom")
	)
	(footprint ""
		(layer "B.Cu")
		(at 93.170502 -205.14945 90)
		(property "Reference" "R534"
			(at 0 0 90)
			(layer "B.SilkS")
			(hide yes)
			(effects
				(font
					(size 1.27 1.27)
				)
				(justify mirror)
			)
		)
		(property "Value" ""
			(at 0 0 90)
			(layer "B.Fab")
			(effects
				(font
					(size 1.27 1.27)
				)
				(justify mirror)
			)
		)
		(duplicate_pad_numbers_are_jumpers no)
		(fp_line
			(start 0.7874 -0.4064)
			(end -0.7874 -0.4064)
			(stroke
				(width 0.1524)
				(type default)
			)
			(layer "B.SilkS")
		)
		(fp_line
			(start -0.7874 -0.4064)
			(end -0.7874 0.4064)
			(stroke
				(width 0.1524)
				(type default)
			)
			(layer "B.SilkS")
		)
		(fp_line
			(start 0.7874 0.4064)
			(end 0.7874 -0.4064)
			(stroke
				(width 0.1524)
				(type default)
			)
			(layer "B.SilkS")
		)
		(fp_line
			(start -0.7874 0.4064)
			(end 0.7874 0.4064)
			(stroke
				(width 0.1524)
				(type default)
			)
			(layer "B.SilkS")
		)
		(fp_line
			(start 0.67945 -0.305054)
			(end 0.12065 -0.305054)
			(stroke
				(width 0.1)
				(type default)
			)
			(layer "B.Fab")
		)
		(fp_line
			(start 0.12065 -0.305054)
			(end 0.12065 -0.2794)
			(stroke
				(width 0.1)
				(type default)
			)
			(layer "B.Fab")
		)
		(fp_line
			(start -0.12065 -0.3048)
			(end -0.67945 -0.3048)
			(stroke
				(width 0.1)
				(type default)
			)
			(layer "B.Fab")
		)
		(fp_line
			(start -0.67945 -0.3048)
			(end -0.67945 0.3048)
			(stroke
				(width 0.1)
				(type default)
			)
			(layer "B.Fab")
		)
		(fp_line
			(start 0.12065 -0.2794)
			(end -0.12065 -0.2794)
			(stroke
				(width 0.1)
				(type default)
			)
			(layer "B.Fab")
		)
		(fp_line
			(start -0.12065 -0.2794)
			(end -0.12065 -0.3048)
			(stroke
				(width 0.1)
				(type default)
			)
			(layer "B.Fab")
		)
		(fp_line
			(start 0.12065 0.2794)
			(end 0.12065 0.3048)
			(stroke
				(width 0.1)
				(type default)
			)
			(layer "B.Fab")
		)
		(fp_line
			(start -0.120396 0.2794)
			(end 0.12065 0.2794)
			(stroke
				(width 0.1)
				(type default)
			)
			(layer "B.Fab")
		)
		(fp_line
			(start 0.67945 0.3048)
			(end 0.67945 -0.305054)
			(stroke
				(width 0.1)
				(type default)
			)
			(layer "B.Fab")
		)
		(fp_line
			(start 0.12065 0.3048)
			(end 0.67945 0.3048)
			(stroke
				(width 0.1)
				(type default)
			)
			(layer "B.Fab")
		)
		(fp_line
			(start -0.120396 0.3048)
			(end -0.120396 0.2794)
			(stroke
				(width 0.1)
				(type default)
			)
			(layer "B.Fab")
		)
		(fp_line
			(start -0.67945 0.3048)
			(end -0.120396 0.3048)
			(stroke
				(width 0.1)
				(type default)
			)
			(layer "B.Fab")
		)
		(pad "1" smd circle
			(at 0.40005 0 270)
			(size 0 0)
			(layers "B.Cu" "B.Mask" "B.Paste")
			(net "CPU1_BP3")
		)
		(pad "2" smd circle
			(at -0.40005 0 270)
			(size 0 0)
			(layers "B.Cu" "B.Mask" "B.Paste")
			(net "PVDD18_S5_P1")
		)
	)
	(footprint ""
		(layer "B.Cu")
		(at 188.087 -143.256 180)
		(property "Reference" "R8033"
			(at 0 0 0)
			(layer "B.SilkS")
			(hide yes)
			(effects
				(font
					(size 1.27 1.27)
				)
				(justify mirror)
			)
		)
		(property "Value" ""
			(at 0 0 0)
			(layer "B.Fab")
			(effects
				(font
					(size 1.27 1.27)
				)
				(justify mirror)
			)
		)
		(duplicate_pad_numbers_are_jumpers no)
		(fp_line
			(start 0.7874 0.4064)
			(end 0.7874 -0.4064)
			(stroke
				(width 0.1524)
				(type default)
			)
			(layer "B.SilkS")
		)
		(fp_line
			(start 0.7874 -0.4064)
			(end -0.7874 -0.4064)
			(stroke
				(width 0.1524)
				(type default)
			)
			(layer "B.SilkS")
		)
		(fp_line
			(start -0.7874 0.4064)
			(end 0.7874 0.4064)
			(stroke
				(width 0.1524)
				(type default)
			)
			(layer "B.SilkS")
		)
		(fp_line
			(start -0.7874 -0.4064)
			(end -0.7874 0.4064)
			(stroke
				(width 0.1524)
				(type default)
			)
			(layer "B.SilkS")
		)
		(fp_line
			(start 0.67945 0.3048)
			(end 0.67945 -0.305054)
			(stroke
				(width 0.1)
				(type default)
			)
			(layer "B.Fab")
		)
		(fp_line
			(start 0.67945 -0.305054)
			(end 0.12065 -0.305054)
			(stroke
				(width 0.1)
				(type default)
			)
			(layer "B.Fab")
		)
		(fp_line
			(start 0.12065 0.3048)
			(end 0.67945 0.3048)
			(stroke
				(width 0.1)
				(type default)
			)
			(layer "B.Fab")
		)
		(fp_line
			(start 0.12065 0.2794)
			(end 0.12065 0.3048)
			(stroke
				(width 0.1)
				(type default)
			)
			(layer "B.Fab")
		)
		(fp_line
			(start 0.12065 -0.2794)
			(end -0.12065 -0.2794)
			(stroke
				(width 0.1)
				(type default)
			)
			(layer "B.Fab")
		)
		(fp_line
			(start 0.12065 -0.305054)
			(end 0.12065 -0.2794)
			(stroke
				(width 0.1)
				(type default)
			)
			(layer "B.Fab")
		)
		(fp_line
			(start -0.120396 0.3048)
			(end -0.120396 0.2794)
			(stroke
				(width 0.1)
				(type default)
			)
			(layer "B.Fab")
		)
		(fp_line
			(start -0.120396 0.2794)
			(end 0.12065 0.2794)
			(stroke
				(width 0.1)
				(type default)
			)
			(layer "B.Fab")
		)
		(fp_line
			(start -0.12065 -0.2794)
			(end -0.12065 -0.3048)
			(stroke
				(width 0.1)
				(type default)
			)
			(layer "B.Fab")
		)
		(fp_line
			(start -0.12065 -0.3048)
			(end -0.67945 -0.3048)
			(stroke
				(width 0.1)
				(type default)
			)
			(layer "B.Fab")
		)
		(fp_line
			(start -0.67945 0.3048)
			(end -0.120396 0.3048)
			(stroke
				(width 0.1)
				(type default)
			)
			(layer "B.Fab")
		)
		(fp_line
			(start -0.67945 -0.3048)
			(end -0.67945 0.3048)
			(stroke
				(width 0.1)
				(type default)
			)
			(layer "B.Fab")
		)
		(pad "1" smd circle
			(at 0.40005 0)
			(size 0 0)
			(layers "B.Cu" "B.Mask" "B.Paste")
			(net "FM_ESPI_CPU0_ALERT_R_SEL")
		)
		(pad "2" smd circle
			(at -0.40005 0)
			(size 0 0)
			(layers "B.Cu" "B.Mask" "B.Paste")
			(net "GND")
		)
	)
	(footprint ""
		(layer "B.Cu")
		(at 413.819086 -398.942052 90)
		(property "Reference" "C805"
			(at 0 0 90)
			(layer "B.SilkS")
			(hide yes)
			(effects
				(font
					(size 1.27 1.27)
				)
				(justify mirror)
			)
		)
		(property "Value" ""
			(at 0 0 90)
			(layer "B.Fab")
			(effects
				(font
					(size 1.27 1.27)
				)
				(justify mirror)
			)
		)
		(duplicate_pad_numbers_are_jumpers no)
		(fp_line
			(start 0.7874 -0.4064)
			(end -0.7874 -0.4064)
			(stroke
				(width 0.1524)
				(type default)
			)
			(layer "B.SilkS")
		)
		(fp_line
			(start -0.7874 -0.4064)
			(end -0.7874 0.4064)
			(stroke
				(width 0.1524)
				(type default)
			)
			(layer "B.SilkS")
		)
		(fp_line
			(start 0.7874 0.4064)
			(end 0.7874 -0.4064)
			(stroke
				(width 0.1524)
				(type default)
			)
			(layer "B.SilkS")
		)
		(fp_line
			(start -0.7874 0.4064)
			(end 0.7874 0.4064)
			(stroke
				(width 0.1524)
				(type default)
			)
			(layer "B.SilkS")
		)
		(fp_line
			(start 0.67945 -0.305054)
			(end 0.12065 -0.305054)
			(stroke
				(width 0.1)
				(type default)
			)
			(layer "B.Fab")
		)
		(fp_line
			(start 0.12065 -0.305054)
			(end 0.12065 -0.2794)
			(stroke
				(width 0.1)
				(type default)
			)
			(layer "B.Fab")
		)
		(fp_line
			(start -0.12065 -0.3048)
			(end -0.67945 -0.3048)
			(stroke
				(width 0.1)
				(type default)
			)
			(layer "B.Fab")
		)
		(fp_line
			(start -0.67945 -0.3048)
			(end -0.67945 0.3048)
			(stroke
				(width 0.1)
				(type default)
			)
			(layer "B.Fab")
		)
		(fp_line
			(start 0.12065 -0.2794)
			(end -0.12065 -0.2794)
			(stroke
				(width 0.1)
				(type default)
			)
			(layer "B.Fab")
		)
		(fp_line
			(start -0.12065 -0.2794)
			(end -0.12065 -0.3048)
			(stroke
				(width 0.1)
				(type default)
			)
			(layer "B.Fab")
		)
		(fp_line
			(start 0.12065 0.2794)
			(end 0.12065 0.3048)
			(stroke
				(width 0.1)
				(type default)
			)
			(layer "B.Fab")
		)
		(fp_line
			(start -0.120396 0.2794)
			(end 0.12065 0.2794)
			(stroke
				(width 0.1)
				(type default)
			)
			(layer "B.Fab")
		)
		(fp_line
			(start 0.67945 0.3048)
			(end 0.67945 -0.305054)
			(stroke
				(width 0.1)
				(type default)
			)
			(layer "B.Fab")
		)
		(fp_line
			(start 0.12065 0.3048)
			(end 0.67945 0.3048)
			(stroke
				(width 0.1)
				(type default)
			)
			(layer "B.Fab")
		)
		(fp_line
			(start -0.120396 0.3048)
			(end -0.120396 0.2794)
			(stroke
				(width 0.1)
				(type default)
			)
			(layer "B.Fab")
		)
		(fp_line
			(start -0.67945 0.3048)
			(end -0.120396 0.3048)
			(stroke
				(width 0.1)
				(type default)
			)
			(layer "B.Fab")
		)
		(pad "1" smd circle
			(at 0.40005 0 270)
			(size 0 0)
			(layers "B.Cu" "B.Mask" "B.Paste")
			(net "P0V9_CPU0_RT_2D")
		)
		(pad "2" smd circle
			(at -0.40005 0 270)
			(size 0 0)
			(layers "B.Cu" "B.Mask" "B.Paste")
			(net "GND")
		)
	)
	(footprint ""
		(layer "B.Cu")
		(at 369.587272 -399.722848 -90)
		(property "Reference" "C1054"
			(at 0 0 90)
			(layer "B.SilkS")
			(hide yes)
			(effects
				(font
					(size 1.27 1.27)
				)
				(justify mirror)
			)
		)
		(property "Value" ""
			(at 0 0 90)
			(layer "B.Fab")
			(effects
				(font
					(size 1.27 1.27)
				)
				(justify mirror)
			)
		)
		(duplicate_pad_numbers_are_jumpers no)
		(fp_line
			(start -0.7874 0.4064)
			(end 0.7874 0.4064)
			(stroke
				(width 0.1524)
				(type default)
			)
			(layer "B.SilkS")
		)
		(fp_line
			(start 0.7874 0.4064)
			(end 0.7874 -0.4064)
			(stroke
				(width 0.1524)
				(type default)
			)
			(layer "B.SilkS")
		)
		(fp_line
			(start -0.7874 -0.4064)
			(end -0.7874 0.4064)
			(stroke
				(width 0.1524)
				(type default)
			)
			(layer "B.SilkS")
		)
		(fp_line
			(start 0.7874 -0.4064)
			(end -0.7874 -0.4064)
			(stroke
				(width 0.1524)
				(type default)
			)
			(layer "B.SilkS")
		)
		(fp_line
			(start -0.67945 0.3048)
			(end -0.120396 0.3048)
			(stroke
				(width 0.1)
				(type default)
			)
			(layer "B.Fab")
		)
		(fp_line
			(start -0.120396 0.3048)
			(end -0.120396 0.2794)
			(stroke
				(width 0.1)
				(type default)
			)
			(layer "B.Fab")
		)
		(fp_line
			(start 0.12065 0.3048)
			(end 0.67945 0.3048)
			(stroke
				(width 0.1)
				(type default)
			)
			(layer "B.Fab")
		)
		(fp_line
			(start 0.67945 0.3048)
			(end 0.67945 -0.305054)
			(stroke
				(width 0.1)
				(type default)
			)
			(layer "B.Fab")
		)
		(fp_line
			(start -0.120396 0.2794)
			(end 0.12065 0.2794)
			(stroke
				(width 0.1)
				(type default)
			)
			(layer "B.Fab")
		)
		(fp_line
			(start 0.12065 0.2794)
			(end 0.12065 0.3048)
			(stroke
				(width 0.1)
				(type default)
			)
			(layer "B.Fab")
		)
		(fp_line
			(start -0.12065 -0.2794)
			(end -0.12065 -0.3048)
			(stroke
				(width 0.1)
				(type default)
			)
			(layer "B.Fab")
		)
		(fp_line
			(start 0.12065 -0.2794)
			(end -0.12065 -0.2794)
			(stroke
				(width 0.1)
				(type default)
			)
			(layer "B.Fab")
		)
		(fp_line
			(start -0.67945 -0.3048)
			(end -0.67945 0.3048)
			(stroke
				(width 0.1)
				(type default)
			)
			(layer "B.Fab")
		)
		(fp_line
			(start -0.12065 -0.3048)
			(end -0.67945 -0.3048)
			(stroke
				(width 0.1)
				(type default)
			)
			(layer "B.Fab")
		)
		(fp_line
			(start 0.12065 -0.305054)
			(end 0.12065 -0.2794)
			(stroke
				(width 0.1)
				(type default)
			)
			(layer "B.Fab")
		)
		(fp_line
			(start 0.67945 -0.305054)
			(end 0.12065 -0.305054)
			(stroke
				(width 0.1)
				(type default)
			)
			(layer "B.Fab")
		)
		(pad "1" smd circle
			(at 0.40005 0 90)
			(size 0 0)
			(layers "B.Cu" "B.Mask" "B.Paste")
			(net "P0V9_CPU0_RT3_2A")
		)
		(pad "2" smd circle
			(at -0.40005 0 90)
			(size 0 0)
			(layers "B.Cu" "B.Mask" "B.Paste")
			(net "GND")
		)
	)
	(footprint ""
		(layer "B.Cu")
		(at 147.261834 -203.679552 -90)
		(property "Reference" "C234"
			(at 0 0 90)
			(layer "B.SilkS")
			(hide yes)
			(effects
				(font
					(size 1.27 1.27)
				)
				(justify mirror)
			)
		)
		(property "Value" ""
			(at 0 0 90)
			(layer "B.Fab")
			(effects
				(font
					(size 1.27 1.27)
				)
				(justify mirror)
			)
		)
		(duplicate_pad_numbers_are_jumpers no)
		(fp_line
			(start -0.7874 0.4064)
			(end 0.7874 0.4064)
			(stroke
				(width 0.1524)
				(type default)
			)
			(layer "B.SilkS")
		)
		(fp_line
			(start 0.7874 0.4064)
			(end 0.7874 -0.4064)
			(stroke
				(width 0.1524)
				(type default)
			)
			(layer "B.SilkS")
		)
		(fp_line
			(start -0.7874 -0.4064)
			(end -0.7874 0.4064)
			(stroke
				(width 0.1524)
				(type default)
			)
			(layer "B.SilkS")
		)
		(fp_line
			(start 0.7874 -0.4064)
			(end -0.7874 -0.4064)
			(stroke
				(width 0.1524)
				(type default)
			)
			(layer "B.SilkS")
		)
		(fp_line
			(start -0.67945 0.3048)
			(end -0.120396 0.3048)
			(stroke
				(width 0.1)
				(type default)
			)
			(layer "B.Fab")
		)
		(fp_line
			(start -0.120396 0.3048)
			(end -0.120396 0.2794)
			(stroke
				(width 0.1)
				(type default)
			)
			(layer "B.Fab")
		)
		(fp_line
			(start 0.12065 0.3048)
			(end 0.67945 0.3048)
			(stroke
				(width 0.1)
				(type default)
			)
			(layer "B.Fab")
		)
		(fp_line
			(start 0.67945 0.3048)
			(end 0.67945 -0.305054)
			(stroke
				(width 0.1)
				(type default)
			)
			(layer "B.Fab")
		)
		(fp_line
			(start -0.120396 0.2794)
			(end 0.12065 0.2794)
			(stroke
				(width 0.1)
				(type default)
			)
			(layer "B.Fab")
		)
		(fp_line
			(start 0.12065 0.2794)
			(end 0.12065 0.3048)
			(stroke
				(width 0.1)
				(type default)
			)
			(layer "B.Fab")
		)
		(fp_line
			(start -0.12065 -0.2794)
			(end -0.12065 -0.3048)
			(stroke
				(width 0.1)
				(type default)
			)
			(layer "B.Fab")
		)
		(fp_line
			(start 0.12065 -0.2794)
			(end -0.12065 -0.2794)
			(stroke
				(width 0.1)
				(type default)
			)
			(layer "B.Fab")
		)
		(fp_line
			(start -0.67945 -0.3048)
			(end -0.67945 0.3048)
			(stroke
				(width 0.1)
				(type default)
			)
			(layer "B.Fab")
		)
		(fp_line
			(start -0.12065 -0.3048)
			(end -0.67945 -0.3048)
			(stroke
				(width 0.1)
				(type default)
			)
			(layer "B.Fab")
		)
		(fp_line
			(start 0.12065 -0.305054)
			(end 0.12065 -0.2794)
			(stroke
				(width 0.1)
				(type default)
			)
			(layer "B.Fab")
		)
		(fp_line
			(start 0.67945 -0.305054)
			(end 0.12065 -0.305054)
			(stroke
				(width 0.1)
				(type default)
			)
			(layer "B.Fab")
		)
		(pad "1" smd circle
			(at 0.40005 0 90)
			(size 0 0)
			(layers "B.Cu" "B.Mask" "B.Paste")
			(net "JTAG_CPU1_TMS")
		)
		(pad "2" smd circle
			(at -0.40005 0 90)
			(size 0 0)
			(layers "B.Cu" "B.Mask" "B.Paste")
			(net "GND")
		)
	)
	(footprint ""
		(layer "B.Cu")
		(at 421.090344 -392.684762 -90)
		(property "Reference" "C987"
			(at 0 0 90)
			(layer "B.SilkS")
			(hide yes)
			(effects
				(font
					(size 1.27 1.27)
				)
				(justify mirror)
			)
		)
		(property "Value" ""
			(at 0 0 90)
			(layer "B.Fab")
			(effects
				(font
					(size 1.27 1.27)
				)
				(justify mirror)
			)
		)
		(duplicate_pad_numbers_are_jumpers no)
		(fp_line
			(start -0.299974 0.150114)
			(end 0.299974 0.150114)
			(stroke
				(width 0.1)
				(type default)
			)
			(layer "B.Fab")
		)
		(fp_line
			(start 0.299974 0.150114)
			(end 0.299974 -0.150114)
			(stroke
				(width 0.1)
				(type default)
			)
			(layer "B.Fab")
		)
		(fp_line
			(start -0.299974 -0.150114)
			(end -0.299974 0.150114)
			(stroke
				(width 0.1)
				(type default)
			)
			(layer "B.Fab")
		)
		(fp_line
			(start 0.299974 -0.150114)
			(end -0.299974 -0.150114)
			(stroke
				(width 0.1)
				(type default)
			)
			(layer "B.Fab")
		)
		(pad "1" smd rect
			(at 0.2667 0 90)
			(size 0.3048 0.381)
			(layers "B.Cu" "B.Mask" "B.Paste")
			(net "P0V9_CPU0_RT2_2A")
		)
		(pad "2" smd rect
			(at -0.2667 0 90)
			(size 0.3048 0.381)
			(layers "B.Cu" "B.Mask" "B.Paste")
			(net "GND")
		)
	)
	(footprint ""
		(layer "B.Cu")
		(at 197.98665 -193.996564)
		(property "Reference" "C176"
			(at 0 0 0)
			(layer "B.SilkS")
			(hide yes)
			(effects
				(font
					(size 1.27 1.27)
				)
				(justify mirror)
			)
		)
		(property "Value" ""
			(at 0 0 0)
			(layer "B.Fab")
			(effects
				(font
					(size 1.27 1.27)
				)
				(justify mirror)
			)
		)
		(duplicate_pad_numbers_are_jumpers no)
		(fp_line
			(start -0.7874 -0.4064)
			(end -0.7874 0.4064)
			(stroke
				(width 0.1524)
				(type default)
			)
			(layer "B.SilkS")
		)
		(fp_line
			(start -0.7874 0.4064)
			(end 0.7874 0.4064)
			(stroke
				(width 0.1524)
				(type default)
			)
			(layer "B.SilkS")
		)
		(fp_line
			(start 0.7874 -0.4064)
			(end -0.7874 -0.4064)
			(stroke
				(width 0.1524)
				(type default)
			)
			(layer "B.SilkS")
		)
		(fp_line
			(start 0.7874 0.4064)
			(end 0.7874 -0.4064)
			(stroke
				(width 0.1524)
				(type default)
			)
			(layer "B.SilkS")
		)
		(fp_line
			(start -0.67945 -0.3048)
			(end -0.67945 0.3048)
			(stroke
				(width 0.1)
				(type default)
			)
			(layer "B.Fab")
		)
		(fp_line
			(start -0.67945 0.3048)
			(end -0.120396 0.3048)
			(stroke
				(width 0.1)
				(type default)
			)
			(layer "B.Fab")
		)
		(fp_line
			(start -0.12065 -0.3048)
			(end -0.67945 -0.3048)
			(stroke
				(width 0.1)
				(type default)
			)
			(layer "B.Fab")
		)
		(fp_line
			(start -0.12065 -0.2794)
			(end -0.12065 -0.3048)
			(stroke
				(width 0.1)
				(type default)
			)
			(layer "B.Fab")
		)
		(fp_line
			(start -0.120396 0.2794)
			(end 0.12065 0.2794)
			(stroke
				(width 0.1)
				(type default)
			)
			(layer "B.Fab")
		)
		(fp_line
			(start -0.120396 0.3048)
			(end -0.120396 0.2794)
			(stroke
				(width 0.1)
				(type default)
			)
			(layer "B.Fab")
		)
		(fp_line
			(start 0.12065 -0.305054)
			(end 0.12065 -0.2794)
			(stroke
				(width 0.1)
				(type default)
			)
			(layer "B.Fab")
		)
		(fp_line
			(start 0.12065 -0.2794)
			(end -0.12065 -0.2794)
			(stroke
				(width 0.1)
				(type default)
			)
			(layer "B.Fab")
		)
		(fp_line
			(start 0.12065 0.2794)
			(end 0.12065 0.3048)
			(stroke
				(width 0.1)
				(type default)
			)
			(layer "B.Fab")
		)
		(fp_line
			(start 0.12065 0.3048)
			(end 0.67945 0.3048)
			(stroke
				(width 0.1)
				(type default)
			)
			(layer "B.Fab")
		)
		(fp_line
			(start 0.67945 -0.305054)
			(end 0.12065 -0.305054)
			(stroke
				(width 0.1)
				(type default)
			)
			(layer "B.Fab")
		)
		(fp_line
			(start 0.67945 0.3048)
			(end 0.67945 -0.305054)
			(stroke
				(width 0.1)
				(type default)
			)
			(layer "B.Fab")
		)
		(pad "1" smd circle
			(at 0.40005 0 180)
			(size 0 0)
			(layers "B.Cu" "B.Mask" "B.Paste")
			(net "P3V3_AUX")
		)
		(pad "2" smd circle
			(at -0.40005 0 180)
			(size 0 0)
			(layers "B.Cu" "B.Mask" "B.Paste")
			(net "GND")
		)
	)
)
